# T6G (Grand Teton) — schematic netlist excerpt (pin names and nets, part order shuffled) for the footprints in the layout excerpt that follows; sources: Cadence DE-HDL packaged netlist, KiCad conversion of 04192023_DAF0TMB3IC0_F0TG_MB_C_brd_V02_OCP.brd

PC634_4  Q_CAP  22UF 4V 20% X6S  pkg C0805  page 223 : A = PVDDIO_P1 ; B = GND
PC442_1  Q_CAP  22UF 16V 20% X6S  pkg C0805  page 222 : A = SW_P12V_AUX_PVDDIO_P1_FLT ; B = GND
R730  Q_RES  10K 5% CHIP  pkg 0402LF  page 76 : A = PVDD18_S5_P1 ; B = SPI_CPU1_CLK

(kicad_pcb
	(version 20260206)
	(generator "pcbnew")
	(generator_version "10.0")
	(general
		(thickness 1.6)
		(legacy_teardrops no)
	)
	(paper "A4")
	(title_block
		(title "04192023_DAF0TMB3IC0_F0TG_MB_C_brd_V02_OCP.brd")
		(comment 1 "Grand Teton / footprints 5665-5667 of 8354")
	)
	(layers
		(0 "F.Cu" signal "TOP")
		(4 "In1.Cu" signal "GND")
		(6 "In2.Cu" signal "IN1")
		(8 "In3.Cu" signal "GND1")
		(10 "In4.Cu" signal "IN2")
		(12 "In5.Cu" signal "GND2")
		(14 "In6.Cu" signal "IN3")
		(16 "In7.Cu" signal "GND3")
		(18 "In8.Cu" signal "VCC")
		(20 "In9.Cu" signal "VCC1")
		(22 "In10.Cu" signal "GND4")
		(24 "In11.Cu" signal "IN4")
		(26 "In12.Cu" signal "GND5")
		(28 "In13.Cu" signal "IN5")
		(30 "In14.Cu" signal "GND6")
		(32 "In15.Cu" signal "IN6")
		(34 "In16.Cu" signal "GND7")
		(2 "B.Cu" signal "BOTTOM")
		(9 "F.Adhes" user "F.Adhesive")
		(11 "B.Adhes" user "B.Adhesive")
		(13 "F.Paste" user "Package Geometry/Pastemask Top")
		(15 "B.Paste" user "Package Geometry/Pastemask Bottom")
		(5 "F.SilkS" user "Ref Des/Silkscreen Top")
		(7 "B.SilkS" user "Ref Des/Silkscreen Bottom")
		(1 "F.Mask" user "Board Geometry/Soldermask Top")
		(3 "B.Mask" user "Board Geometry/Soldermask Bottom")
		(17 "Dwgs.User" user "User.Drawings")
		(19 "Cmts.User" user "User.Comments")
		(21 "Eco1.User" user "User.Eco1")
		(23 "Eco2.User" user "User.Eco2")
		(25 "Edge.Cuts" user "Board Geometry/Outline")
		(27 "Margin" user)
		(31 "F.CrtYd" user "Package Geometry/Place Bound Top")
		(29 "B.CrtYd" user "Package Geometry/Place Bound Bottom")
		(35 "F.Fab" user "Ref Des/Assembly Top")
		(33 "B.Fab" user "Ref Des/Assembly Bottom")
	)
	(footprint ""
		(layer "B.Cu")
		(at 54.665118 -350.660716 -90)
		(property "Reference" "PC442_1"
			(at 0 0 90)
			(layer "B.SilkS")
			(hide yes)
			(effects
				(font
					(size 1.27 1.27)
				)
				(justify mirror)
			)
		)
		(property "Value" ""
			(at 0 0 90)
			(layer "B.Fab")
			(effects
				(font
					(size 1.27 1.27)
				)
				(justify mirror)
			)
		)
		(duplicate_pad_numbers_are_jumpers no)
		(fp_line
			(start -1.524 0.762)
			(end 1.524 0.762)
			(stroke
				(width 0.1524)
				(type default)
			)
			(layer "B.SilkS")
		)
		(fp_line
			(start 1.524 0.762)
			(end 1.524 -0.762)
			(stroke
				(width 0.1524)
				(type default)
			)
			(layer "B.SilkS")
		)
		(fp_line
			(start -1.524 -0.762)
			(end -1.524 0.762)
			(stroke
				(width 0.1524)
				(type default)
			)
			(layer "B.SilkS")
		)
		(fp_line
			(start 1.524 -0.762)
			(end -1.524 -0.762)
			(stroke
				(width 0.1524)
				(type default)
			)
			(layer "B.SilkS")
		)
		(fp_line
			(start -1.1049 0.724916)
			(end -1.1049 -0.724916)
			(stroke
				(width 0.1)
				(type default)
			)
			(layer "B.Fab")
		)
		(fp_line
			(start 1.1049 0.724916)
			(end -1.1049 0.724916)
			(stroke
				(width 0.1)
				(type default)
			)
			(layer "B.Fab")
		)
		(fp_line
			(start -1.1049 -0.724916)
			(end 1.1049 -0.724916)
			(stroke
				(width 0.1)
				(type default)
			)
			(layer "B.Fab")
		)
		(fp_line
			(start 1.1049 -0.724916)
			(end 1.1049 0.724916)
			(stroke
				(width 0.1)
				(type default)
			)
			(layer "B.Fab")
		)
		(pad "1" smd rect
			(at 0.889 0 270)
			(size 1.016 1.27)
			(layers "B.Cu" "B.Mask" "B.Paste")
			(net "SW_P12V_AUX_PVDDIO_P1_FLT")
		)
		(pad "2" smd rect
			(at -0.889 0 270)
			(size 1.016 1.27)
			(layers "B.Cu" "B.Mask" "B.Paste")
			(net "GND")
		)
	)
	(footprint ""
		(layer "B.Cu")
		(at 24.890476 -337.985354 -90)
		(property "Reference" "PC634_4"
			(at 0 0 90)
			(layer "B.SilkS")
			(hide yes)
			(effects
				(font
					(size 1.27 1.27)
				)
				(justify mirror)
			)
		)
		(property "Value" ""
			(at 0 0 90)
			(layer "B.Fab")
			(effects
				(font
					(size 1.27 1.27)
				)
				(justify mirror)
			)
		)
		(duplicate_pad_numbers_are_jumpers no)
		(fp_line
			(start -1.524 0.762)
			(end 1.524 0.762)
			(stroke
				(width 0.1524)
				(type default)
			)
			(layer "B.SilkS")
		)
		(fp_line
			(start 1.524 0.762)
			(end 1.524 -0.762)
			(stroke
				(width 0.1524)
				(type default)
			)
			(layer "B.SilkS")
		)
		(fp_line
			(start -1.524 -0.762)
			(end -1.524 0.762)
			(stroke
				(width 0.1524)
				(type default)
			)
			(layer "B.SilkS")
		)
		(fp_line
			(start 1.524 -0.762)
			(end -1.524 -0.762)
			(stroke
				(width 0.1524)
				(type default)
			)
			(layer "B.SilkS")
		)
		(fp_line
			(start -1.1049 0.724916)
			(end -1.1049 -0.724916)
			(stroke
				(width 0.1)
				(type default)
			)
			(layer "B.Fab")
		)
		(fp_line
			(start 1.1049 0.724916)
			(end -1.1049 0.724916)
			(stroke
				(width 0.1)
				(type default)
			)
			(layer "B.Fab")
		)
		(fp_line
			(start -1.1049 -0.724916)
			(end 1.1049 -0.724916)
			(stroke
				(width 0.1)
				(type default)
			)
			(layer "B.Fab")
		)
		(fp_line
			(start 1.1049 -0.724916)
			(end 1.1049 0.724916)
			(stroke
				(width 0.1)
				(type default)
			)
			(layer "B.Fab")
		)
		(pad "1" smd rect
			(at 0.889 0 270)
			(size 1.016 1.27)
			(layers "B.Cu" "B.Mask" "B.Paste")
			(net "PVDDIO_P1")
		)
		(pad "2" smd rect
			(at -0.889 0 270)
			(size 1.016 1.27)
			(layers "B.Cu" "B.Mask" "B.Paste")
			(net "GND")
		)
	)
	(footprint ""
		(layer "B.Cu")
		(at 152.849834 -322.903342 -90)
		(property "Reference" "R730"
			(at 0 0 90)
			(layer "B.SilkS")
			(hide yes)
			(effects
				(font
					(size 1.27 1.27)
				)
				(justify mirror)
			)
		)
		(property "Value" ""
			(at 0 0 90)
			(layer "B.Fab")
			(effects
				(font
					(size 1.27 1.27)
				)
				(justify mirror)
			)
		)
		(duplicate_pad_numbers_are_jumpers no)
		(fp_line
			(start -0.7874 0.4064)
			(end 0.7874 0.4064)
			(stroke
				(width 0.1524)
				(type default)
			)
			(layer "B.SilkS")
		)
		(fp_line
			(start 0.7874 0.4064)
			(end 0.7874 -0.4064)
			(stroke
				(width 0.1524)
				(type default)
			)
			(layer "B.SilkS")
		)
		(fp_line
			(start -0.7874 -0.4064)
			(end -0.7874 0.4064)
			(stroke
				(width 0.1524)
				(type default)
			)
			(layer "B.SilkS")
		)
		(fp_line
			(start 0.7874 -0.4064)
			(end -0.7874 -0.4064)
			(stroke
				(width 0.1524)
				(type default)
			)
			(layer "B.SilkS")
		)
		(fp_line
			(start -0.67945 0.3048)
			(end -0.120396 0.3048)
			(stroke
				(width 0.1)
				(type default)
			)
			(layer "B.Fab")
		)
		(fp_line
			(start -0.120396 0.3048)
			(end -0.120396 0.2794)
			(stroke
				(width 0.1)
				(type default)
			)
			(layer "B.Fab")
		)
		(fp_line
			(start 0.12065 0.3048)
			(end 0.67945 0.3048)
			(stroke
				(width 0.1)
				(type default)
			)
			(layer "B.Fab")
		)
		(fp_line
			(start 0.67945 0.3048)
			(end 0.67945 -0.305054)
			(stroke
				(width 0.1)
				(type default)
			)
			(layer "B.Fab")
		)
		(fp_line
			(start -0.120396 0.2794)
			(end 0.12065 0.2794)
			(stroke
				(width 0.1)
				(type default)
			)
			(layer "B.Fab")
		)
		(fp_line
			(start 0.12065 0.2794)
			(end 0.12065 0.3048)
			(stroke
				(width 0.1)
				(type default)
			)
			(layer "B.Fab")
		)
		(fp_line
			(start -0.12065 -0.2794)
			(end -0.12065 -0.3048)
			(stroke
				(width 0.1)
				(type default)
			)
			(layer "B.Fab")
		)
		(fp_line
			(start 0.12065 -0.2794)
			(end -0.12065 -0.2794)
			(stroke
				(width 0.1)
				(type default)
			)
			(layer "B.Fab")
		)
		(fp_line
			(start -0.67945 -0.3048)
			(end -0.67945 0.3048)
			(stroke
				(width 0.1)
				(type default)
			)
			(layer "B.Fab")
		)
		(fp_line
			(start -0.12065 -0.3048)
			(end -0.67945 -0.3048)
			(stroke
				(width 0.1)
				(type default)
			)
			(layer "B.Fab")
		)
		(fp_line
			(start 0.12065 -0.305054)
			(end 0.12065 -0.2794)
			(stroke
				(width 0.1)
				(type default)
			)
			(layer "B.Fab")
		)
		(fp_line
			(start 0.67945 -0.305054)
			(end 0.12065 -0.305054)
			(stroke
				(width 0.1)
				(type default)
			)
			(layer "B.Fab")
		)
		(pad "1" smd circle
			(at 0.40005 0 90)
			(size 0 0)
			(layers "B.Cu" "B.Mask" "B.Paste")
			(net "PVDD18_S5_P1")
		)
		(pad "2" smd circle
			(at -0.40005 0 90)
			(size 0 0)
			(layers "B.Cu" "B.Mask" "B.Paste")
			(net "SPI_CPU1_CLK")
		)
	)
)
